# S9S_MB_2U (Grand Teton) — schematic netlist excerpt (pin names and nets, part order shuffled) for the footprints in the layout excerpt that follows; sources: Cadence DE-HDL packaged netlist, KiCad conversion of 03242023_DA0F0TMBIJ0_F0T_Motherboard_J_brd_V01_OCP.brd

PU35  ISL69260IRAZT  ISL69260IRAZ-T IC  pkg QFN40_TH_0-4_5X5XE  page 278
  PWM0  = NC_PVCCD_HV_CPU0_APWM8
  PWM1  = NC_PVCCD_HV_CPU0_APWM7
  PWM2  = NC_PVCCD_HV_CPU0_APWM6
  PWM3  = NC_PVCCD_HV_CPU0_APWM5
  PWM4  = NC_PVCCD_HV_CPU0_APWM4
  PWM5  = NC_PVCCD_HV_CPU0_APWM3
  PWM6  = NC_PVCCD_HV_CPU0_APWM2
  PWM7  = PVCCD_HV_CPU0_APWM1
  PMSDA  = SMB_DIO_PVCCD_HV_CPU0
  PMSCL  = SMB_CLK_PVCCD_HV_CPU0
  \npmalert#\  = NC_PVCCD_HV_CPU0_SMB_ALERT
  PG0  = PWRGD_PVCCD_HV_CPU0_R
  EN0  = PVCCD_HV_CPU0_EN_R
  \nvrhot#\  = IRQ_PVCCD_CPU0_VRHOT_LVC3_R_N
  \npinalert#||npsyscrit#\  = PVCCD_HV_CPU0_PIN_ALT
  PG1  = NC_PVCCD_HV_CPU0_BVR_RDY
  SVCLK  = SVID_CLK_PVCCD_HV_CPU0_R
  SVDATA  = SVID_DIO_PVCCD_HV_CPU0_R
  \nsvalert#\  = SVID_ALERT_PVCCD_HV_CPU0_R
  EN1  = GND
  VSEN0  = SH_PVCCD_HV_CPU0_R
  RGND0  = VSENSE_PVCCD_HV_CPU0_DN
  CS7  = PVCCD_HV_CPU0_ACSP1
  CS6  = NC_PVCCD_HV_CPU0_ACSP2
  CS5  = NC_PVCCD_HV_CPU0_ACSP3
  CS4  = NC_PVCCD_HV_CPU0_ACSP4
  CS3  = NC_PVCCD_HV_CPU0_ACSP5
  CS2  = NC_PVCCD_HV_CPU0_ACSP6
  CS1  = NC_PVCCD_HV_CPU0_ACSP7
  CS0  = NC_PVCCD_HV_CPU0_ACSP8
  RGND1  = GND
  VSEN1  = GND
  CFP  = PVCCD_HV_CPU0_FAULT
  ADDR_CFG  = PVCCD_HV_CPU0_ADDR
  TEMP0  = PVCCD_HV_CPU0_ATSEN
  \temp1||isys\  = PVCCD_HV_CPU0_ISYS_R
  \vmon||iinsen||vsys||isys\  = PVCCD_HV_CPU0_ISENSE_P
  \vinsen||vsys\  = PVCCD_HV_CPU0_ISENSE_N
  VCC  = PVCCD_HV_CPU0_VCC
  VCCS  = PVCCD_HV_CPU0_VREF
  TH_GND  = GND

(kicad_pcb
	(version 20260206)
	(generator "pcbnew")
	(generator_version "10.0")
	(general
		(thickness 1.6)
		(legacy_teardrops no)
	)
	(paper "A4")
	(title_block
		(title "03242023_DA0F0TMBIJ0_F0T_Motherboard_J_brd_V01_OCP.brd")
		(comment 1 "Grand Teton / footprint 1251 of 6105 (PU35), pads 1-41 of 41")
	)
	(layers
		(0 "F.Cu" signal "TOP")
		(4 "In1.Cu" signal "GND")
		(6 "In2.Cu" signal "IN1")
		(8 "In3.Cu" signal "GND1")
		(10 "In4.Cu" signal "IN2")
		(12 "In5.Cu" signal "GND2")
		(14 "In6.Cu" signal "IN3")
		(16 "In7.Cu" signal "GND3")
		(18 "In8.Cu" signal "VCC")
		(20 "In9.Cu" signal "VCC1")
		(22 "In10.Cu" signal "GND4")
		(24 "In11.Cu" signal "IN4")
		(26 "In12.Cu" signal "GND5")
		(28 "In13.Cu" signal "IN5")
		(30 "In14.Cu" signal "GND6")
		(32 "In15.Cu" signal "IN6")
		(34 "In16.Cu" signal "GND7")
		(2 "B.Cu" signal "BOTTOM")
		(9 "F.Adhes" user "F.Adhesive")
		(11 "B.Adhes" user "B.Adhesive")
		(13 "F.Paste" user "Package Geometry/Pastemask Top")
		(15 "B.Paste" user "Package Geometry/Pastemask Bottom")
		(5 "F.SilkS" user "Ref Des/Silkscreen Top")
		(7 "B.SilkS" user "Ref Des/Silkscreen Bottom")
		(1 "F.Mask" user "Board Geometry/Soldermask Top")
		(3 "B.Mask" user "Board Geometry/Soldermask Bottom")
		(17 "Dwgs.User" user "User.Drawings")
		(19 "Cmts.User" user "User.Comments")
		(21 "Eco1.User" user "User.Eco1")
		(23 "Eco2.User" user "User.Eco2")
		(25 "Edge.Cuts" user "Board Geometry/Outline")
		(27 "Margin" user)
		(31 "F.CrtYd" user "Package Geometry/Place Bound Top")
		(29 "B.CrtYd" user "Package Geometry/Place Bound Bottom")
		(35 "F.Fab" user "Ref Des/Assembly Top")
		(33 "B.Fab" user "Ref Des/Assembly Bottom")
	)
	(footprint ""
		(layer "F.Cu")
		(at 432.50104 -122.988578 90)
		(property "Reference" "PU35"
			(at -1.01219 -8.547354 0)
			(unlocked yes)
			(layer "F.SilkS")
			(effects
				(font
					(size 0.7874 0.5842)
					(thickness 0.1524)
				)
				(justify left)
			)
		)
		(property "Value" ""
			(at 0 0 90)
			(layer "F.Fab")
			(effects
				(font
					(size 1.27 1.27)
				)
			)
		)
		(duplicate_pad_numbers_are_jumpers no)
		(pad "1" smd rect
			(at -2.400046 -1.800098)
			(size 0.1778 0.6096)
			(layers "F.Cu" "F.Mask" "F.Paste")
			(net "NC_PVCCD_HV_CPU0_APWM8")
		)
		(pad "2" smd rect
			(at -2.400046 -1.400048)
			(size 0.1778 0.6096)
			(layers "F.Cu" "F.Mask" "F.Paste")
			(net "NC_PVCCD_HV_CPU0_APWM7")
		)
		(pad "3" smd rect
			(at -2.400046 -0.999998)
			(size 0.1778 0.6096)
			(layers "F.Cu" "F.Mask" "F.Paste")
			(net "NC_PVCCD_HV_CPU0_APWM6")
		)
		(pad "4" smd rect
			(at -2.400046 -0.599948)
			(size 0.1778 0.6096)
			(layers "F.Cu" "F.Mask" "F.Paste")
			(net "NC_PVCCD_HV_CPU0_APWM5")
		)
		(pad "5" smd rect
			(at -2.400046 -0.199898)
			(size 0.1778 0.6096)
			(layers "F.Cu" "F.Mask" "F.Paste")
			(net "NC_PVCCD_HV_CPU0_APWM4")
		)
		(pad "6" smd rect
			(at -2.400046 0.199898)
			(size 0.1778 0.6096)
			(layers "F.Cu" "F.Mask" "F.Paste")
			(net "NC_PVCCD_HV_CPU0_APWM3")
		)
		(pad "7" smd rect
			(at -2.400046 0.599948)
			(size 0.1778 0.6096)
			(layers "F.Cu" "F.Mask" "F.Paste")
			(net "NC_PVCCD_HV_CPU0_APWM2")
		)
		(pad "8" smd rect
			(at -2.400046 0.999998)
			(size 0.1778 0.6096)
			(layers "F.Cu" "F.Mask" "F.Paste")
			(net "PVCCD_HV_CPU0_APWM1")
		)
		(pad "9" smd rect
			(at -2.400046 1.400048)
			(size 0.1778 0.6096)
			(layers "F.Cu" "F.Mask" "F.Paste")
			(net "SMB_DIO_PVCCD_HV_CPU0")
		)
		(pad "10" smd rect
			(at -2.400046 1.800098)
			(size 0.1778 0.6096)
			(layers "F.Cu" "F.Mask" "F.Paste")
			(net "SMB_CLK_PVCCD_HV_CPU0")
		)
		(pad "11" smd rect
			(at -1.800098 2.400046 90)
			(size 0.1778 0.6096)
			(layers "F.Cu" "F.Mask" "F.Paste")
			(net "NC_PVCCD_HV_CPU0_SMB_ALERT")
		)
		(pad "12" smd rect
			(at -1.400048 2.400046 90)
			(size 0.1778 0.6096)
			(layers "F.Cu" "F.Mask" "F.Paste")
			(net "PWRGD_PVCCD_HV_CPU0_R")
		)
		(pad "13" smd rect
			(at -0.999998 2.400046 90)
			(size 0.1778 0.6096)
			(layers "F.Cu" "F.Mask" "F.Paste")
			(net "PVCCD_HV_CPU0_EN_R")
		)
		(pad "14" smd rect
			(at -0.599948 2.400046 90)
			(size 0.1778 0.6096)
			(layers "F.Cu" "F.Mask" "F.Paste")
			(net "IRQ_PVCCD_CPU0_VRHOT_LVC3_R_N")
		)
		(pad "15" smd rect
			(at -0.199898 2.400046 90)
			(size 0.1778 0.6096)
			(layers "F.Cu" "F.Mask" "F.Paste")
			(net "PVCCD_HV_CPU0_PIN_ALT")
		)
		(pad "16" smd rect
			(at 0.199898 2.400046 90)
			(size 0.1778 0.6096)
			(layers "F.Cu" "F.Mask" "F.Paste")
			(net "NC_PVCCD_HV_CPU0_BVR_RDY")
		)
		(pad "17" smd rect
			(at 0.599948 2.400046 90)
			(size 0.1778 0.6096)
			(layers "F.Cu" "F.Mask" "F.Paste")
			(net "SVID_CLK_PVCCD_HV_CPU0_R")
		)
		(pad "18" smd rect
			(at 0.999998 2.400046 90)
			(size 0.1778 0.6096)
			(layers "F.Cu" "F.Mask" "F.Paste")
			(net "SVID_DIO_PVCCD_HV_CPU0_R")
		)
		(pad "19" smd rect
			(at 1.400048 2.400046 90)
			(size 0.1778 0.6096)
			(layers "F.Cu" "F.Mask" "F.Paste")
			(net "SVID_ALERT_PVCCD_HV_CPU0_R")
		)
		(pad "20" smd rect
			(at 1.800098 2.400046 90)
			(size 0.1778 0.6096)
			(layers "F.Cu" "F.Mask" "F.Paste")
			(net "GND")
		)
		(pad "21" smd rect
			(at 2.400046 1.800098)
			(size 0.1778 0.6096)
			(layers "F.Cu" "F.Mask" "F.Paste")
			(net "SH_PVCCD_HV_CPU0_R")
		)
		(pad "22" smd rect
			(at 2.400046 1.400048)
			(size 0.1778 0.6096)
			(layers "F.Cu" "F.Mask" "F.Paste")
			(net "VSENSE_PVCCD_HV_CPU0_DN")
		)
		(pad "23" smd rect
			(at 2.400046 0.999998)
			(size 0.1778 0.6096)
			(layers "F.Cu" "F.Mask" "F.Paste")
			(net "PVCCD_HV_CPU0_ACSP1")
		)
		(pad "24" smd rect
			(at 2.400046 0.599948)
			(size 0.1778 0.6096)
			(layers "F.Cu" "F.Mask" "F.Paste")
			(net "NC_PVCCD_HV_CPU0_ACSP2")
		)
		(pad "25" smd rect
			(at 2.400046 0.199898)
			(size 0.1778 0.6096)
			(layers "F.Cu" "F.Mask" "F.Paste")
			(net "NC_PVCCD_HV_CPU0_ACSP3")
		)
		(pad "26" smd rect
			(at 2.400046 -0.199898)
			(size 0.1778 0.6096)
			(layers "F.Cu" "F.Mask" "F.Paste")
			(net "NC_PVCCD_HV_CPU0_ACSP4")
		)
		(pad "27" smd rect
			(at 2.400046 -0.599948)
			(size 0.1778 0.6096)
			(layers "F.Cu" "F.Mask" "F.Paste")
			(net "NC_PVCCD_HV_CPU0_ACSP5")
		)
		(pad "28" smd rect
			(at 2.400046 -0.999998)
			(size 0.1778 0.6096)
			(layers "F.Cu" "F.Mask" "F.Paste")
			(net "NC_PVCCD_HV_CPU0_ACSP6")
		)
		(pad "29" smd rect
			(at 2.400046 -1.400048)
			(size 0.1778 0.6096)
			(layers "F.Cu" "F.Mask" "F.Paste")
			(net "NC_PVCCD_HV_CPU0_ACSP7")
		)
		(pad "30" smd rect
			(at 2.400046 -1.800098)
			(size 0.1778 0.6096)
			(layers "F.Cu" "F.Mask" "F.Paste")
			(net "NC_PVCCD_HV_CPU0_ACSP8")
		)
		(pad "31" smd rect
			(at 1.800098 -2.400046 90)
			(size 0.1778 0.6096)
			(layers "F.Cu" "F.Mask" "F.Paste")
			(net "GND")
		)
		(pad "32" smd rect
			(at 1.400048 -2.400046 90)
			(size 0.1778 0.6096)
			(layers "F.Cu" "F.Mask" "F.Paste")
			(net "GND")
		)
		(pad "33" smd rect
			(at 0.999998 -2.400046 90)
			(size 0.1778 0.6096)
			(layers "F.Cu" "F.Mask" "F.Paste")
			(net "PVCCD_HV_CPU0_FAULT")
		)
		(pad "34" smd rect
			(at 0.599948 -2.400046 90)
			(size 0.1778 0.6096)
			(layers "F.Cu" "F.Mask" "F.Paste")
			(net "PVCCD_HV_CPU0_ADDR")
		)
		(pad "35" smd rect
			(at 0.199898 -2.400046 90)
			(size 0.1778 0.6096)
			(layers "F.Cu" "F.Mask" "F.Paste")
			(net "PVCCD_HV_CPU0_ATSEN")
		)
		(pad "36" smd rect
			(at -0.199898 -2.400046 90)
			(size 0.1778 0.6096)
			(layers "F.Cu" "F.Mask" "F.Paste")
			(net "PVCCD_HV_CPU0_ISYS_R")
		)
		(pad "37" smd rect
			(at -0.599948 -2.400046 90)
			(size 0.1778 0.6096)
			(layers "F.Cu" "F.Mask" "F.Paste")
			(net "PVCCD_HV_CPU0_ISENSE_P")
		)
		(pad "38" smd rect
			(at -0.999998 -2.400046 90)
			(size 0.1778 0.6096)
			(layers "F.Cu" "F.Mask" "F.Paste")
			(net "PVCCD_HV_CPU0_ISENSE_N")
		)
		(pad "39" smd rect
			(at -1.400048 -2.400046 90)
			(size 0.1778 0.6096)
			(layers "F.Cu" "F.Mask" "F.Paste")
			(net "PVCCD_HV_CPU0_VCC")
		)
		(pad "40" smd rect
			(at -1.800098 -2.400046 90)
			(size 0.1778 0.6096)
			(layers "F.Cu" "F.Mask" "F.Paste")
			(net "PVCCD_HV_CPU0_VREF")
		)
		(pad "TH" smd rect
			(at 0 0 90)
			(size 3.6576 3.6576)
			(layers "F.Cu" "F.Mask" "F.Paste")
			(net "GND")
		)
	)
)
